# SCM (Grand Teton) — schematic netlist excerpt (pin names and nets, part order shuffled) for the footprints in the layout excerpt that follows; sources: Cadence DE-HDL packaged netlist, KiCad conversion of 12092022_DA0F0TMDCD0_F0T_Management_Board_D_brd_V3_OCP.brd

PL19  Q_INDUCTOR  BLM18SN220TN1D/8000MA IND  pkg SMLF  page 52 : \1\ = P12V_AUX ; \2\ = SW_P3V3_AUX_FLT
R177  Q_RES  33.2 1% CHIP  pkg 0402LF  page 13 : A = H_CPU1_PROCHOT_LVC1_N ; B = H_CPU1_PROCHOT_LVC1_R_N

(kicad_pcb
	(version 20260206)
	(generator "pcbnew")
	(generator_version "10.0")
	(general
		(thickness 1.6)
		(legacy_teardrops no)
	)
	(paper "A4")
	(title_block
		(title "12092022_DA0F0TMDCD0_F0T_Management_Board_D_brd_V3_OCP.brd")
		(comment 1 "Grand Teton / footprints 217-218 of 1440")
	)
	(layers
		(0 "F.Cu" signal "TOP")
		(4 "In1.Cu" signal "GND")
		(6 "In2.Cu" signal "IN1")
		(8 "In3.Cu" signal "GND1")
		(10 "In4.Cu" signal "IN2")
		(12 "In5.Cu" signal "VCC")
		(14 "In6.Cu" signal "VCC1")
		(16 "In7.Cu" signal "IN3")
		(18 "In8.Cu" signal "GND2")
		(20 "In9.Cu" signal "IN4")
		(22 "In10.Cu" signal "GND3")
		(2 "B.Cu" signal "BOTTOM")
		(9 "F.Adhes" user "F.Adhesive")
		(11 "B.Adhes" user "B.Adhesive")
		(13 "F.Paste" user "Package Geometry/Pastemask Top")
		(15 "B.Paste" user "Package Geometry/Pastemask Bottom")
		(5 "F.SilkS" user "Ref Des/Silkscreen Top")
		(7 "B.SilkS" user "Ref Des/Silkscreen Bottom")
		(1 "F.Mask" user "Board Geometry/Soldermask Top")
		(3 "B.Mask" user "Board Geometry/Soldermask Bottom")
		(17 "Dwgs.User" user "User.Drawings")
		(19 "Cmts.User" user "User.Comments")
		(21 "Eco1.User" user "User.Eco1")
		(23 "Eco2.User" user "User.Eco2")
		(25 "Edge.Cuts" user "Board Geometry/Outline")
		(27 "Margin" user)
		(31 "F.CrtYd" user "Package Geometry/Place Bound Top")
		(29 "B.CrtYd" user "Package Geometry/Place Bound Bottom")
		(35 "F.Fab" user "Ref Des/Assembly Top")
		(33 "B.Fab" user "Ref Des/Assembly Bottom")
	)
	(footprint ""
		(layer "F.Cu")
		(at 39.9542 -48.6918 180)
		(property "Reference" "R177"
			(at 0 0 180)
			(layer "F.SilkS")
			(hide yes)
			(effects
				(font
					(size 1.27 1.27)
				)
			)
		)
		(property "Value" ""
			(at 0 0 180)
			(layer "F.Fab")
			(effects
				(font
					(size 1.27 1.27)
				)
			)
		)
		(duplicate_pad_numbers_are_jumpers no)
		(fp_line
			(start 0.7874 0.4064)
			(end -0.7874 0.4064)
			(stroke
				(width 0.1524)
				(type default)
			)
			(layer "F.SilkS")
		)
		(fp_line
			(start 0.7874 -0.4064)
			(end 0.7874 0.4064)
			(stroke
				(width 0.1524)
				(type default)
			)
			(layer "F.SilkS")
		)
		(fp_line
			(start -0.7874 0.4064)
			(end -0.7874 -0.4064)
			(stroke
				(width 0.1524)
				(type default)
			)
			(layer "F.SilkS")
		)
		(fp_line
			(start -0.7874 -0.4064)
			(end 0.7874 -0.4064)
			(stroke
				(width 0.1524)
				(type default)
			)
			(layer "F.SilkS")
		)
		(fp_line
			(start 0.67945 0.3048)
			(end 0.120396 0.3048)
			(stroke
				(width 0.1)
				(type default)
			)
			(layer "F.Fab")
		)
		(fp_line
			(start 0.67945 -0.3048)
			(end 0.67945 0.3048)
			(stroke
				(width 0.1)
				(type default)
			)
			(layer "F.Fab")
		)
		(fp_line
			(start 0.12065 -0.2794)
			(end 0.12065 -0.3048)
			(stroke
				(width 0.1)
				(type default)
			)
			(layer "F.Fab")
		)
		(fp_line
			(start 0.12065 -0.3048)
			(end 0.67945 -0.3048)
			(stroke
				(width 0.1)
				(type default)
			)
			(layer "F.Fab")
		)
		(fp_line
			(start 0.120396 0.3048)
			(end 0.120396 0.2794)
			(stroke
				(width 0.1)
				(type default)
			)
			(layer "F.Fab")
		)
		(fp_line
			(start 0.120396 0.2794)
			(end -0.12065 0.2794)
			(stroke
				(width 0.1)
				(type default)
			)
			(layer "F.Fab")
		)
		(fp_line
			(start -0.12065 0.3048)
			(end -0.67945 0.3048)
			(stroke
				(width 0.1)
				(type default)
			)
			(layer "F.Fab")
		)
		(fp_line
			(start -0.12065 0.2794)
			(end -0.12065 0.3048)
			(stroke
				(width 0.1)
				(type default)
			)
			(layer "F.Fab")
		)
		(fp_line
			(start -0.12065 -0.2794)
			(end 0.12065 -0.2794)
			(stroke
				(width 0.1)
				(type default)
			)
			(layer "F.Fab")
		)
		(fp_line
			(start -0.12065 -0.305054)
			(end -0.12065 -0.2794)
			(stroke
				(width 0.1)
				(type default)
			)
			(layer "F.Fab")
		)
		(fp_line
			(start -0.67945 0.3048)
			(end -0.67945 -0.305054)
			(stroke
				(width 0.1)
				(type default)
			)
			(layer "F.Fab")
		)
		(fp_line
			(start -0.67945 -0.305054)
			(end -0.12065 -0.305054)
			(stroke
				(width 0.1)
				(type default)
			)
			(layer "F.Fab")
		)
		(pad "1" smd circle
			(at -0.40005 0 180)
			(size 0 0)
			(layers "F.Cu" "F.Mask" "F.Paste")
			(net "H_CPU1_PROCHOT_LVC1_N")
		)
		(pad "2" smd circle
			(at 0.40005 0 180)
			(size 0 0)
			(layers "F.Cu" "F.Mask" "F.Paste")
			(net "H_CPU1_PROCHOT_LVC1_R_N")
		)
	)
	(footprint ""
		(layer "F.Cu")
		(at 9.65581 -57.393332 180)
		(property "Reference" "PL19"
			(at 0 0 180)
			(layer "F.SilkS")
			(hide yes)
			(effects
				(font
					(size 1.27 1.27)
				)
			)
		)
		(property "Value" ""
			(at 0 0 180)
			(layer "F.Fab")
			(effects
				(font
					(size 1.27 1.27)
				)
			)
		)
		(duplicate_pad_numbers_are_jumpers no)
		(fp_line
			(start 1.27 0.5842)
			(end 1.27 -0.5842)
			(stroke
				(width 0.1524)
				(type default)
			)
			(layer "F.SilkS")
		)
		(fp_line
			(start 1.27 0.5842)
			(end -1.27 0.5842)
			(stroke
				(width 0.1524)
				(type default)
			)
			(layer "F.SilkS")
		)
		(fp_line
			(start 0.127 0.5842)
			(end 0.127 -0.5842)
			(stroke
				(width 0.1524)
				(type default)
			)
			(layer "F.SilkS")
		)
		(fp_line
			(start -0.127 0.5842)
			(end -0.127 -0.5842)
			(stroke
				(width 0.1524)
				(type default)
			)
			(layer "F.SilkS")
		)
		(fp_line
			(start -1.27 0.5842)
			(end -1.27 -0.5842)
			(stroke
				(width 0.1524)
				(type default)
			)
			(layer "F.SilkS")
		)
		(fp_line
			(start -1.27 -0.5588)
			(end -1.27 -0.5842)
			(stroke
				(width 0.1524)
				(type default)
			)
			(layer "F.SilkS")
		)
		(fp_line
			(start -1.27 -0.5842)
			(end 1.27 -0.5842)
			(stroke
				(width 0.1524)
				(type default)
			)
			(layer "F.SilkS")
		)
		(fp_line
			(start 1.1938 0.4064)
			(end 0.9144 0.4064)
			(stroke
				(width 0.1)
				(type default)
			)
			(layer "F.Fab")
		)
		(fp_line
			(start 1.1938 -0.406654)
			(end 1.1938 0.4064)
			(stroke
				(width 0.1)
				(type default)
			)
			(layer "F.Fab")
		)
		(fp_line
			(start 0.9144 0.508)
			(end -0.9144 0.508)
			(stroke
				(width 0.1)
				(type default)
			)
			(layer "F.Fab")
		)
		(fp_line
			(start 0.9144 0.4064)
			(end 0.9144 0.508)
			(stroke
				(width 0.1)
				(type default)
			)
			(layer "F.Fab")
		)
		(fp_line
			(start 0.9144 -0.406654)
			(end 1.1938 -0.406654)
			(stroke
				(width 0.1)
				(type default)
			)
			(layer "F.Fab")
		)
		(fp_line
			(start 0.9144 -0.508)
			(end 0.9144 -0.406654)
			(stroke
				(width 0.1)
				(type default)
			)
			(layer "F.Fab")
		)
		(fp_line
			(start -0.9144 0.508)
			(end -0.9144 0.406654)
			(stroke
				(width 0.1)
				(type default)
			)
			(layer "F.Fab")
		)
		(fp_line
			(start -0.9144 0.406654)
			(end -1.194308 0.406654)
			(stroke
				(width 0.1)
				(type default)
			)
			(layer "F.Fab")
		)
		(fp_line
			(start -0.9144 -0.406654)
			(end -0.9144 -0.508)
			(stroke
				(width 0.1)
				(type default)
			)
			(layer "F.Fab")
		)
		(fp_line
			(start -0.9144 -0.508)
			(end 0.9144 -0.508)
			(stroke
				(width 0.1)
				(type default)
			)
			(layer "F.Fab")
		)
		(fp_line
			(start -1.194308 0.406654)
			(end -1.194308 -0.406654)
			(stroke
				(width 0.1)
				(type default)
			)
			(layer "F.Fab")
		)
		(fp_line
			(start -1.194308 -0.406654)
			(end -0.9144 -0.406654)
			(stroke
				(width 0.1)
				(type default)
			)
			(layer "F.Fab")
		)
		(pad "1" smd rect
			(at -0.7366 0 90)
			(size 0.7112 0.8128)
			(layers "F.Cu" "F.Mask" "F.Paste")
			(net "P12V_AUX")
		)
		(pad "2" smd rect
			(at 0.7366 0 90)
			(size 0.7112 0.8128)
			(layers "F.Cu" "F.Mask" "F.Paste")
			(net "SW_P3V3_AUX_FLT")
		)
	)
)
